(kicad_pcb
	(version 20260206)
	(generator "pcbnew")
	(generator_version "10.0")
	(general
		(thickness 1.6)
		(legacy_teardrops no)
	)
	(paper "A4")
	(title_block
		(title "15969-1a.1015WZS0858.brd")
		(comment 1 "Tioga Pass / footprints 130-136 of 295")
	)
	(layers
		(0 "F.Cu" signal "TOP")
		(4 "In1.Cu" signal "L2GND")
		(6 "In2.Cu" signal "L3")
		(8 "In3.Cu" signal "L4")
		(10 "In4.Cu" signal "L5GND")
		(2 "B.Cu" signal "BOTTOM")
		(9 "F.Adhes" user "F.Adhesive")
		(11 "B.Adhes" user "B.Adhesive")
		(13 "F.Paste" user "Package Geometry/Pastemask Top")
		(15 "B.Paste" user "Package Geometry/Pastemask Bottom")
		(5 "F.SilkS" user "Ref Des/Silkscreen Top")
		(7 "B.SilkS" user "Ref Des/Silkscreen Bottom")
		(1 "F.Mask" user "Board Geometry/Soldermask Top")
		(3 "B.Mask" user "Board Geometry/Soldermask Bottom")
		(17 "Dwgs.User" user "User.Drawings")
		(19 "Cmts.User" user "User.Comments")
		(21 "Eco1.User" user "User.Eco1")
		(23 "Eco2.User" user "User.Eco2")
		(25 "Edge.Cuts" user "Board Geometry/Outline")
		(27 "Margin" user)
		(31 "F.CrtYd" user "Package Geometry/Place Bound Top")
		(29 "B.CrtYd" user "Package Geometry/Place Bound Bottom")
		(35 "F.Fab" user "Ref Des/Assembly Top")
		(33 "B.Fab" user "Ref Des/Assembly Bottom")
	)
	(footprint ""
		(layer "F.Cu")
		(at 62.9666 -16.1798 90)
		(property "Reference" "R46"
			(at 0 0 90)
			(layer "F.SilkS")
			(hide yes)
			(effects
				(font
					(size 1.27 1.27)
				)
			)
		)
		(property "Value" "4K7R2F-GP"
			(at 0.064008 -3.993896 90)
			(unlocked yes)
			(layer "F.Fab")
			(hide yes)
			(effects
				(font
					(size 1.016 1.016)
					(thickness 0.1524)
				)
			)
		)
		(property "Device Type" "R402H16"
			(at 0.064008 -5.517896 90)
			(unlocked yes)
			(layer "F.Fab")
			(hide yes)
			(effects
				(font
					(size 1.016 1.016)
					(thickness 0.1524)
				)
			)
		)
		(duplicate_pad_numbers_are_jumpers no)
		(fp_line
			(start 0.508 -0.9398)
			(end -0.508 -0.9398)
			(stroke
				(width 0.1524)
				(type default)
			)
			(layer "F.SilkS")
		)
		(fp_line
			(start -0.508 -0.9398)
			(end -0.508 0.9398)
			(stroke
				(width 0.1524)
				(type default)
			)
			(layer "F.SilkS")
		)
		(fp_rect
			(start -0.508 0.9398)
			(end 0.508 -0.9398)
			(stroke
				(width 0)
				(type default)
			)
			(fill no)
			(layer "F.CrtYd")
		)
		(fp_rect
			(start -0.508 0.9398)
			(end 0.508 -0.9398)
			(stroke
				(width 0)
				(type default)
			)
			(fill no)
			(layer "F.Fab")
		)
		(pad "1" smd custom
			(at 0 -0.4445 90)
			(size 0.1397 0.1397)
			(layers "F.Cu" "F.Mask" "F.Paste")
			(net "P3V3_STBY")
			(options
				(clearance outline)
				(anchor circle)
			)
			(primitives
				(gr_poly
					(pts
						(arc
							(start -0.1778 -0.2794)
							(mid -0.249642 -0.249642)
							(end -0.2794 -0.1778)
						)
						(arc
							(start -0.2794 0.1778)
							(mid -0.249642 0.249642)
							(end -0.1778 0.2794)
						)
						(arc
							(start 0.1778 0.2794)
							(mid 0.249642 0.249642)
							(end 0.2794 0.1778)
						)
						(arc
							(start 0.2794 -0.1778)
							(mid 0.249642 -0.249642)
							(end 0.1778 -0.2794)
						)
					)
					(width 0)
					(fill yes)
				)
			)
		)
		(pad "2" smd custom
			(at 0 0.4445 90)
			(size 0.1397 0.1397)
			(layers "F.Cu" "F.Mask" "F.Paste")
			(net "PCIE_SLOT2_PRSNT2_2_N")
			(options
				(clearance outline)
				(anchor circle)
			)
			(primitives
				(gr_poly
					(pts
						(arc
							(start -0.1778 -0.2794)
							(mid -0.249642 -0.249642)
							(end -0.2794 -0.1778)
						)
						(arc
							(start -0.2794 0.1778)
							(mid -0.249642 0.249642)
							(end -0.1778 0.2794)
						)
						(arc
							(start 0.1778 0.2794)
							(mid 0.249642 0.249642)
							(end 0.2794 0.1778)
						)
						(arc
							(start 0.2794 -0.1778)
							(mid 0.249642 -0.249642)
							(end 0.1778 -0.2794)
						)
					)
					(width 0)
					(fill yes)
				)
			)
		)
	)
	(footprint ""
		(layer "F.Cu")
		(at 38.2397 1.9177 90)
		(property "Reference" "R167"
			(at 0 0 90)
			(layer "F.SilkS")
			(hide yes)
			(effects
				(font
					(size 1.27 1.27)
				)
			)
		)
		(property "Value" "4K7R2F-GP"
			(at 0.064008 -3.993896 90)
			(unlocked yes)
			(layer "F.Fab")
			(hide yes)
			(effects
				(font
					(size 1.016 1.016)
					(thickness 0.1524)
				)
			)
		)
		(property "Device Type" "R402H16"
			(at 0.064008 -5.517896 90)
			(unlocked yes)
			(layer "F.Fab")
			(hide yes)
			(effects
				(font
					(size 1.016 1.016)
					(thickness 0.1524)
				)
			)
		)
		(duplicate_pad_numbers_are_jumpers no)
		(fp_line
			(start 0.508 -0.9398)
			(end -0.508 -0.9398)
			(stroke
				(width 0.1524)
				(type default)
			)
			(layer "F.SilkS")
		)
		(fp_line
			(start -0.508 -0.9398)
			(end -0.508 0.9398)
			(stroke
				(width 0.1524)
				(type default)
			)
			(layer "F.SilkS")
		)
		(fp_rect
			(start -0.508 0.9398)
			(end 0.508 -0.9398)
			(stroke
				(width 0)
				(type default)
			)
			(fill no)
			(layer "F.CrtYd")
		)
		(fp_rect
			(start -0.508 0.9398)
			(end 0.508 -0.9398)
			(stroke
				(width 0)
				(type default)
			)
			(fill no)
			(layer "F.Fab")
		)
		(pad "1" smd custom
			(at 0 -0.4445 90)
			(size 0.1397 0.1397)
			(layers "F.Cu" "F.Mask" "F.Paste")
			(net "P3V3")
			(options
				(clearance outline)
				(anchor circle)
			)
			(primitives
				(gr_poly
					(pts
						(arc
							(start -0.1778 -0.2794)
							(mid -0.249642 -0.249642)
							(end -0.2794 -0.1778)
						)
						(arc
							(start -0.2794 0.1778)
							(mid -0.249642 0.249642)
							(end -0.1778 0.2794)
						)
						(arc
							(start 0.1778 0.2794)
							(mid 0.249642 0.249642)
							(end 0.2794 0.1778)
						)
						(arc
							(start 0.2794 -0.1778)
							(mid 0.249642 -0.249642)
							(end 0.1778 -0.2794)
						)
					)
					(width 0)
					(fill yes)
				)
			)
		)
		(pad "2" smd custom
			(at 0 0.4445 90)
			(size 0.1397 0.1397)
			(layers "F.Cu" "F.Mask" "F.Paste")
			(net "SMB_PCH_ALERT")
			(options
				(clearance outline)
				(anchor circle)
			)
			(primitives
				(gr_poly
					(pts
						(arc
							(start -0.1778 -0.2794)
							(mid -0.249642 -0.249642)
							(end -0.2794 -0.1778)
						)
						(arc
							(start -0.2794 0.1778)
							(mid -0.249642 0.249642)
							(end -0.1778 0.2794)
						)
						(arc
							(start 0.1778 0.2794)
							(mid 0.249642 0.249642)
							(end 0.2794 0.1778)
						)
						(arc
							(start 0.2794 -0.1778)
							(mid 0.249642 -0.249642)
							(end 0.1778 -0.2794)
						)
					)
					(width 0)
					(fill yes)
				)
			)
		)
	)
	(footprint ""
		(layer "F.Cu")
		(at 20.7772 -23.5204 180)
		(property "Reference" "C52"
			(at 0 0 180)
			(layer "F.SilkS")
			(hide yes)
			(effects
				(font
					(size 1.27 1.27)
				)
			)
		)
		(property "Value" "SCD1U16V2KX-3GP"
			(at 1.1811 -2.7051 180)
			(unlocked yes)
			(layer "F.Fab")
			(hide yes)
			(effects
				(font
					(size 1.016 1.016)
					(thickness 0.1524)
				)
			)
		)
		(property "Device Type" "C402H22"
			(at 1.1811 -4.2291 180)
			(unlocked yes)
			(layer "F.Fab")
			(hide yes)
			(effects
				(font
					(size 1.016 1.016)
					(thickness 0.1524)
				)
			)
		)
		(duplicate_pad_numbers_are_jumpers no)
		(fp_rect
			(start -0.4318 0.9525)
			(end 0.4318 -0.9525)
			(stroke
				(width 0)
				(type default)
			)
			(fill no)
			(layer "F.CrtYd")
		)
		(fp_rect
			(start -0.4318 0.9525)
			(end 0.4318 -0.9525)
			(stroke
				(width 0)
				(type default)
			)
			(fill no)
			(layer "F.Fab")
		)
		(pad "1" smd custom
			(at 0 -0.4445 180)
			(size 0.1524 0.1524)
			(layers "F.Cu" "F.Mask" "F.Paste")
			(net "P3V3_STBY")
			(options
				(clearance outline)
				(anchor circle)
			)
			(primitives
				(gr_poly
					(pts
						(arc
							(start 0.3048 -0.2032)
							(mid 0.275042 -0.275042)
							(end 0.2032 -0.3048)
						)
						(arc
							(start -0.2032 -0.3048)
							(mid -0.275042 -0.275042)
							(end -0.3048 -0.2032)
						)
						(arc
							(start -0.3048 0.2032)
							(mid -0.275042 0.275042)
							(end -0.2032 0.3048)
						)
						(arc
							(start 0.2032 0.3048)
							(mid 0.275042 0.275042)
							(end 0.3048 0.2032)
						)
					)
					(width 0)
					(fill yes)
				)
			)
		)
		(pad "2" smd custom
			(at 0 0.4445 180)
			(size 0.1524 0.1524)
			(layers "F.Cu" "F.Mask" "F.Paste")
			(net "GND")
			(options
				(clearance outline)
				(anchor circle)
			)
			(primitives
				(gr_poly
					(pts
						(arc
							(start 0.3048 -0.2032)
							(mid 0.275042 -0.275042)
							(end 0.2032 -0.3048)
						)
						(arc
							(start -0.2032 -0.3048)
							(mid -0.275042 -0.275042)
							(end -0.3048 -0.2032)
						)
						(arc
							(start -0.3048 0.2032)
							(mid -0.275042 0.275042)
							(end -0.2032 0.3048)
						)
						(arc
							(start 0.2032 0.3048)
							(mid 0.275042 0.275042)
							(end 0.3048 0.2032)
						)
					)
					(width 0)
					(fill yes)
				)
			)
		)
	)
	(footprint ""
		(layer "F.Cu")
		(at 114.6048 0.3048 180)
		(property "Reference" "R11"
			(at 0 0 180)
			(layer "F.SilkS")
			(hide yes)
			(effects
				(font
					(size 1.27 1.27)
				)
			)
		)
		(property "Value" "4K7R2F-GP"
			(at 0.064008 -3.993896 180)
			(unlocked yes)
			(layer "F.Fab")
			(hide yes)
			(effects
				(font
					(size 1.016 1.016)
					(thickness 0.1524)
				)
			)
		)
		(property "Device Type" "R402H16"
			(at 0.064008 -5.517896 180)
			(unlocked yes)
			(layer "F.Fab")
			(hide yes)
			(effects
				(font
					(size 1.016 1.016)
					(thickness 0.1524)
				)
			)
		)
		(duplicate_pad_numbers_are_jumpers no)
		(fp_line
			(start 0.508 -0.9398)
			(end -0.508 -0.9398)
			(stroke
				(width 0.1524)
				(type default)
			)
			(layer "F.SilkS")
		)
		(fp_line
			(start -0.508 -0.9398)
			(end -0.508 0.9398)
			(stroke
				(width 0.1524)
				(type default)
			)
			(layer "F.SilkS")
		)
		(fp_rect
			(start -0.508 0.9398)
			(end 0.508 -0.9398)
			(stroke
				(width 0)
				(type default)
			)
			(fill no)
			(layer "F.CrtYd")
		)
		(fp_rect
			(start -0.508 0.9398)
			(end 0.508 -0.9398)
			(stroke
				(width 0)
				(type default)
			)
			(fill no)
			(layer "F.Fab")
		)
		(pad "1" smd custom
			(at 0 -0.4445 180)
			(size 0.1397 0.1397)
			(layers "F.Cu" "F.Mask" "F.Paste")
			(net "P3V3_STBY")
			(options
				(clearance outline)
				(anchor circle)
			)
			(primitives
				(gr_poly
					(pts
						(arc
							(start -0.1778 -0.2794)
							(mid -0.249642 -0.249642)
							(end -0.2794 -0.1778)
						)
						(arc
							(start -0.2794 0.1778)
							(mid -0.249642 0.249642)
							(end -0.1778 0.2794)
						)
						(arc
							(start 0.1778 0.2794)
							(mid 0.249642 0.249642)
							(end 0.2794 0.1778)
						)
						(arc
							(start 0.2794 -0.1778)
							(mid 0.249642 -0.249642)
							(end 0.1778 -0.2794)
						)
					)
					(width 0)
					(fill yes)
				)
			)
		)
		(pad "2" smd custom
			(at 0 0.4445 180)
			(size 0.1397 0.1397)
			(layers "F.Cu" "F.Mask" "F.Paste")
			(net "PU_B_MUX_SCL2")
			(options
				(clearance outline)
				(anchor circle)
			)
			(primitives
				(gr_poly
					(pts
						(arc
							(start -0.1778 -0.2794)
							(mid -0.249642 -0.249642)
							(end -0.2794 -0.1778)
						)
						(arc
							(start -0.2794 0.1778)
							(mid -0.249642 0.249642)
							(end -0.1778 0.2794)
						)
						(arc
							(start 0.1778 0.2794)
							(mid 0.249642 0.249642)
							(end 0.2794 0.1778)
						)
						(arc
							(start 0.2794 -0.1778)
							(mid 0.249642 -0.249642)
							(end 0.1778 -0.2794)
						)
					)
					(width 0)
					(fill yes)
				)
			)
		)
	)
	(footprint ""
		(layer "F.Cu")
		(at 129.1082 0.4826 180)
		(property "Reference" "R68"
			(at 0 0 180)
			(layer "F.SilkS")
			(hide yes)
			(effects
				(font
					(size 1.27 1.27)
				)
			)
		)
		(property "Value" "0R2F-1-GP"
			(at 0.064008 -3.993896 180)
			(unlocked yes)
			(layer "F.Fab")
			(hide yes)
			(effects
				(font
					(size 1.016 1.016)
					(thickness 0.1524)
				)
			)
		)
		(property "Device Type" "R402H16"
			(at 0.064008 -5.517896 180)
			(unlocked yes)
			(layer "F.Fab")
			(hide yes)
			(effects
				(font
					(size 1.016 1.016)
					(thickness 0.1524)
				)
			)
		)
		(duplicate_pad_numbers_are_jumpers no)
		(fp_line
			(start 0.508 -0.9398)
			(end -0.508 -0.9398)
			(stroke
				(width 0.1524)
				(type default)
			)
			(layer "F.SilkS")
		)
		(fp_line
			(start -0.508 -0.9398)
			(end -0.508 0.9398)
			(stroke
				(width 0.1524)
				(type default)
			)
			(layer "F.SilkS")
		)
		(fp_rect
			(start -0.508 0.9398)
			(end 0.508 -0.9398)
			(stroke
				(width 0)
				(type default)
			)
			(fill no)
			(layer "F.CrtYd")
		)
		(fp_rect
			(start -0.508 0.9398)
			(end 0.508 -0.9398)
			(stroke
				(width 0)
				(type default)
			)
			(fill no)
			(layer "F.Fab")
		)
		(pad "1" smd custom
			(at 0 -0.4445 180)
			(size 0.1397 0.1397)
			(layers "F.Cu" "F.Mask" "F.Paste")
			(net "SMCLK_PCH_DEVICE")
			(options
				(clearance outline)
				(anchor circle)
			)
			(primitives
				(gr_poly
					(pts
						(arc
							(start -0.1778 -0.2794)
							(mid -0.249642 -0.249642)
							(end -0.2794 -0.1778)
						)
						(arc
							(start -0.2794 0.1778)
							(mid -0.249642 0.249642)
							(end -0.1778 0.2794)
						)
						(arc
							(start 0.1778 0.2794)
							(mid 0.249642 0.249642)
							(end 0.2794 0.1778)
						)
						(arc
							(start 0.2794 -0.1778)
							(mid 0.249642 -0.249642)
							(end 0.1778 -0.2794)
						)
					)
					(width 0)
					(fill yes)
				)
			)
		)
		(pad "2" smd custom
			(at 0 0.4445 180)
			(size 0.1397 0.1397)
			(layers "F.Cu" "F.Mask" "F.Paste")
			(net "SMCLK_EXP_R_PCH")
			(options
				(clearance outline)
				(anchor circle)
			)
			(primitives
				(gr_poly
					(pts
						(arc
							(start -0.1778 -0.2794)
							(mid -0.249642 -0.249642)
							(end -0.2794 -0.1778)
						)
						(arc
							(start -0.2794 0.1778)
							(mid -0.249642 0.249642)
							(end -0.1778 0.2794)
						)
						(arc
							(start 0.1778 0.2794)
							(mid 0.249642 0.249642)
							(end 0.2794 0.1778)
						)
						(arc
							(start 0.2794 -0.1778)
							(mid 0.249642 -0.249642)
							(end 0.1778 -0.2794)
						)
					)
					(width 0)
					(fill yes)
				)
			)
		)
	)
	(footprint ""
		(layer "F.Cu")
		(at 84.4804 -21.082)
		(property "Reference" "C37"
			(at 0 0 0)
			(layer "F.SilkS")
			(hide yes)
			(effects
				(font
					(size 1.27 1.27)
				)
			)
		)
		(property "Value" "SCD01U16V2KX-3GP"
			(at 1.1811 -2.7051 0)
			(unlocked yes)
			(layer "F.Fab")
			(hide yes)
			(effects
				(font
					(size 1.016 1.016)
					(thickness 0.1524)
				)
			)
		)
		(property "Device Type" "C402H22"
			(at 1.1811 -4.2291 0)
			(unlocked yes)
			(layer "F.Fab")
			(hide yes)
			(effects
				(font
					(size 1.016 1.016)
					(thickness 0.1524)
				)
			)
		)
		(duplicate_pad_numbers_are_jumpers no)
		(fp_rect
			(start -0.4318 0.9525)
			(end 0.4318 -0.9525)
			(stroke
				(width 0)
				(type default)
			)
			(fill no)
			(layer "F.CrtYd")
		)
		(fp_rect
			(start -0.4318 0.9525)
			(end 0.4318 -0.9525)
			(stroke
				(width 0)
				(type default)
			)
			(fill no)
			(layer "F.Fab")
		)
		(pad "1" smd custom
			(at 0 -0.4445)
			(size 0.1524 0.1524)
			(layers "F.Cu" "F.Mask" "F.Paste")
			(net "RESET_IN")
			(options
				(clearance outline)
				(anchor circle)
			)
			(primitives
				(gr_poly
					(pts
						(arc
							(start 0.3048 -0.2032)
							(mid 0.275042 -0.275042)
							(end 0.2032 -0.3048)
						)
						(arc
							(start -0.2032 -0.3048)
							(mid -0.275042 -0.275042)
							(end -0.3048 -0.2032)
						)
						(arc
							(start -0.3048 0.2032)
							(mid -0.275042 0.275042)
							(end -0.2032 0.3048)
						)
						(arc
							(start 0.2032 0.3048)
							(mid 0.275042 0.275042)
							(end 0.3048 0.2032)
						)
					)
					(width 0)
					(fill yes)
				)
			)
		)
		(pad "2" smd custom
			(at 0 0.4445)
			(size 0.1524 0.1524)
			(layers "F.Cu" "F.Mask" "F.Paste")
			(net "GND")
			(options
				(clearance outline)
				(anchor circle)
			)
			(primitives
				(gr_poly
					(pts
						(arc
							(start 0.3048 -0.2032)
							(mid 0.275042 -0.275042)
							(end 0.2032 -0.3048)
						)
						(arc
							(start -0.2032 -0.3048)
							(mid -0.275042 -0.275042)
							(end -0.3048 -0.2032)
						)
						(arc
							(start -0.3048 0.2032)
							(mid -0.275042 0.275042)
							(end -0.2032 0.3048)
						)
						(arc
							(start 0.2032 0.3048)
							(mid 0.275042 0.275042)
							(end 0.3048 0.2032)
						)
					)
					(width 0)
					(fill yes)
				)
			)
		)
	)
	(footprint ""
		(layer "F.Cu")
		(at 105.3084 2.7686)
		(property "Reference" "R15"
			(at 0 0 0)
			(layer "F.SilkS")
			(hide yes)
			(effects
				(font
					(size 1.27 1.27)
				)
			)
		)
		(property "Value" "10KR2F-2-GP"
			(at 0.064008 -3.993896 0)
			(unlocked yes)
			(layer "F.Fab")
			(hide yes)
			(effects
				(font
					(size 1.016 1.016)
					(thickness 0.1524)
				)
			)
		)
		(property "Device Type" "R402H16"
			(at 0.064008 -5.517896 0)
			(unlocked yes)
			(layer "F.Fab")
			(hide yes)
			(effects
				(font
					(size 1.016 1.016)
					(thickness 0.1524)
				)
			)
		)
		(duplicate_pad_numbers_are_jumpers no)
		(fp_line
			(start -0.508 -0.9398)
			(end -0.508 0.9398)
			(stroke
				(width 0.1524)
				(type default)
			)
			(layer "F.SilkS")
		)
		(fp_line
			(start 0.508 -0.9398)
			(end -0.508 -0.9398)
			(stroke
				(width 0.1524)
				(type default)
			)
			(layer "F.SilkS")
		)
		(fp_rect
			(start -0.508 0.9398)
			(end 0.508 -0.9398)
			(stroke
				(width 0)
				(type default)
			)
			(fill no)
			(layer "F.CrtYd")
		)
		(fp_rect
			(start -0.508 0.9398)
			(end 0.508 -0.9398)
			(stroke
				(width 0)
				(type default)
			)
			(fill no)
			(layer "F.Fab")
		)
		(pad "1" smd custom
			(at 0 -0.4445)
			(size 0.1397 0.1397)
			(layers "F.Cu" "F.Mask" "F.Paste")
			(net "SMB_B_HUB_A2")
			(options
				(clearance outline)
				(anchor circle)
			)
			(primitives
				(gr_poly
					(pts
						(arc
							(start -0.1778 -0.2794)
							(mid -0.249642 -0.249642)
							(end -0.2794 -0.1778)
						)
						(arc
							(start -0.2794 0.1778)
							(mid -0.249642 0.249642)
							(end -0.1778 0.2794)
						)
						(arc
							(start 0.1778 0.2794)
							(mid 0.249642 0.249642)
							(end 0.2794 0.1778)
						)
						(arc
							(start 0.2794 -0.1778)
							(mid 0.249642 -0.249642)
							(end 0.1778 -0.2794)
						)
					)
					(width 0)
					(fill yes)
				)
			)
		)
		(pad "2" smd custom
			(at 0 0.4445)
			(size 0.1397 0.1397)
			(layers "F.Cu" "F.Mask" "F.Paste")
			(net "GND")
			(options
				(clearance outline)
				(anchor circle)
			)
			(primitives
				(gr_poly
					(pts
						(arc
							(start -0.1778 -0.2794)
							(mid -0.249642 -0.249642)
							(end -0.2794 -0.1778)
						)
						(arc
							(start -0.2794 0.1778)
							(mid -0.249642 0.249642)
							(end -0.1778 0.2794)
						)
						(arc
							(start 0.1778 0.2794)
							(mid 0.249642 0.249642)
							(end 0.2794 0.1778)
						)
						(arc
							(start 0.2794 -0.1778)
							(mid 0.249642 -0.249642)
							(end 0.1778 -0.2794)
						)
					)
					(width 0)
					(fill yes)
				)
			)
		)
	)
)
